(kicad_pcb
	(version 20260206)
	(generator "pcbnew")
	(generator_version "10.0")
	(general
		(thickness 1.6)
		(legacy_teardrops no)
	)
	(paper "A4")
	(title_block
		(title "04192023_DAF0TMB3IC0_F0TG_MB_C_brd_V02_OCP.brd")
		(comment 1 "Grand Teton / footprints 552-558 of 8354")
	)
	(layers
		(0 "F.Cu" signal "TOP")
		(4 "In1.Cu" signal "GND")
		(6 "In2.Cu" signal "IN1")
		(8 "In3.Cu" signal "GND1")
		(10 "In4.Cu" signal "IN2")
		(12 "In5.Cu" signal "GND2")
		(14 "In6.Cu" signal "IN3")
		(16 "In7.Cu" signal "GND3")
		(18 "In8.Cu" signal "VCC")
		(20 "In9.Cu" signal "VCC1")
		(22 "In10.Cu" signal "GND4")
		(24 "In11.Cu" signal "IN4")
		(26 "In12.Cu" signal "GND5")
		(28 "In13.Cu" signal "IN5")
		(30 "In14.Cu" signal "GND6")
		(32 "In15.Cu" signal "IN6")
		(34 "In16.Cu" signal "GND7")
		(2 "B.Cu" signal "BOTTOM")
		(9 "F.Adhes" user "F.Adhesive")
		(11 "B.Adhes" user "B.Adhesive")
		(13 "F.Paste" user "Package Geometry/Pastemask Top")
		(15 "B.Paste" user "Package Geometry/Pastemask Bottom")
		(5 "F.SilkS" user "Ref Des/Silkscreen Top")
		(7 "B.SilkS" user "Ref Des/Silkscreen Bottom")
		(1 "F.Mask" user "Board Geometry/Soldermask Top")
		(3 "B.Mask" user "Board Geometry/Soldermask Bottom")
		(17 "Dwgs.User" user "User.Drawings")
		(19 "Cmts.User" user "User.Comments")
		(21 "Eco1.User" user "User.Eco1")
		(23 "Eco2.User" user "User.Eco2")
		(25 "Edge.Cuts" user "Board Geometry/Outline")
		(27 "Margin" user)
		(31 "F.CrtYd" user "Package Geometry/Place Bound Top")
		(29 "B.CrtYd" user "Package Geometry/Place Bound Bottom")
		(35 "F.Fab" user "Ref Des/Assembly Top")
		(33 "B.Fab" user "Ref Des/Assembly Bottom")
	)
	(footprint ""
		(layer "F.Cu")
		(at 237.507272 -68.524374 180)
		(property "Reference" "U44"
			(at 1.378204 -2.10566 0)
			(unlocked yes)
			(layer "F.SilkS")
			(effects
				(font
					(size 0.7874 0.5842)
					(thickness 0.1524)
				)
				(justify left)
			)
		)
		(property "Value" ""
			(at 0 0 180)
			(layer "F.Fab")
			(effects
				(font
					(size 1.27 1.27)
				)
			)
		)
		(duplicate_pad_numbers_are_jumpers no)
		(fp_line
			(start 1.695958 1.124966)
			(end -1.695958 1.124966)
			(stroke
				(width 0.1524)
				(type default)
			)
			(layer "F.SilkS")
		)
		(fp_line
			(start 1.695958 -1.124966)
			(end 1.695958 1.124966)
			(stroke
				(width 0.1524)
				(type default)
			)
			(layer "F.SilkS")
		)
		(fp_line
			(start -1.695958 1.124966)
			(end -1.695958 -1.124966)
			(stroke
				(width 0.1524)
				(type default)
			)
			(layer "F.SilkS")
		)
		(fp_line
			(start -1.695958 -1.124966)
			(end 1.695958 -1.124966)
			(stroke
				(width 0.1524)
				(type default)
			)
			(layer "F.SilkS")
		)
		(fp_poly
			(pts
				(xy -2.4892 -0.340106) (xy -2.4892 -0.959866) (xy -1.86944 -0.649986)
			)
			(stroke
				(width 0)
				(type default)
			)
			(fill yes)
			(layer "F.SilkS")
		)
		(fp_line
			(start 0.674878 1.124966)
			(end -0.674878 1.124966)
			(stroke
				(width 0.1)
				(type default)
			)
			(layer "F.Fab")
		)
		(fp_line
			(start 0.674878 -1.124966)
			(end 0.674878 1.124966)
			(stroke
				(width 0.1)
				(type default)
			)
			(layer "F.Fab")
		)
		(fp_line
			(start -0.674878 1.124966)
			(end -0.674878 -1.124966)
			(stroke
				(width 0.1)
				(type default)
			)
			(layer "F.Fab")
		)
		(fp_line
			(start -0.674878 -1.124966)
			(end 0.674878 -1.124966)
			(stroke
				(width 0.1)
				(type default)
			)
			(layer "F.Fab")
		)
		(fp_poly
			(pts
				(xy -2.4892 -0.959866) (xy -1.86944 -0.649986) (xy -2.4892 -0.340106)
			)
			(stroke
				(width 0)
				(type default)
			)
			(fill yes)
			(layer "F.Fab")
		)
		(pad "1" smd rect
			(at -0.94488 -0.649986 270)
			(size 0.3556 1.2446)
			(layers "F.Cu" "F.Mask" "F.Paste")
			(net "Net_10764")
		)
		(pad "2" smd rect
			(at -0.94488 0 270)
			(size 0.3556 1.2446)
			(layers "F.Cu" "F.Mask" "F.Paste")
			(net "FM_LED_ACTIVE_E1S_0_R")
		)
		(pad "3" smd rect
			(at -0.94488 0.649986 270)
			(size 0.3556 1.2446)
			(layers "F.Cu" "F.Mask" "F.Paste")
			(net "GND")
		)
		(pad "4" smd rect
			(at 0.94488 0.649986 270)
			(size 0.3556 1.2446)
			(layers "F.Cu" "F.Mask" "F.Paste")
			(net "FM_LED_ACTIVE_E1S_0_R_BUF")
		)
		(pad "5" smd rect
			(at 0.94488 -0.649986 270)
			(size 0.3556 1.2446)
			(layers "F.Cu" "F.Mask" "F.Paste")
			(net "P3V3_E1S_0")
		)
	)
	(footprint ""
		(layer "F.Cu")
		(at 90.487754 -350.497394 90)
		(property "Reference" "PL42"
			(at -2.671064 3.492246 0)
			(unlocked yes)
			(layer "F.SilkS")
			(effects
				(font
					(size 0.7874 0.5842)
					(thickness 0.1524)
				)
				(justify left)
			)
		)
		(property "Value" ""
			(at 0 0 90)
			(layer "F.Fab")
			(effects
				(font
					(size 1.27 1.27)
				)
			)
		)
		(duplicate_pad_numbers_are_jumpers no)
		(fp_line
			(start 3.050032 -2.999994)
			(end -3.050032 -2.999994)
			(stroke
				(width 0.1524)
				(type default)
			)
			(layer "F.SilkS")
		)
		(fp_line
			(start -3.050032 -2.999994)
			(end -3.050032 -1.4478)
			(stroke
				(width 0.1524)
				(type default)
			)
			(layer "F.SilkS")
		)
		(fp_line
			(start 3.050032 -1.4478)
			(end 3.050032 -2.999994)
			(stroke
				(width 0.1524)
				(type default)
			)
			(layer "F.SilkS")
		)
		(fp_line
			(start -3.050032 1.4478)
			(end -3.050032 2.999994)
			(stroke
				(width 0.1524)
				(type default)
			)
			(layer "F.SilkS")
		)
		(fp_line
			(start 3.050032 2.999994)
			(end 3.050032 1.4478)
			(stroke
				(width 0.1524)
				(type default)
			)
			(layer "F.SilkS")
		)
		(fp_line
			(start -3.050032 2.999994)
			(end 3.050032 2.999994)
			(stroke
				(width 0.1524)
				(type default)
			)
			(layer "F.SilkS")
		)
		(fp_line
			(start 3.050032 -2.999994)
			(end -3.050032 -2.999994)
			(stroke
				(width 0.1)
				(type default)
			)
			(layer "F.Fab")
		)
		(fp_line
			(start -3.050032 -2.999994)
			(end -3.050032 2.999994)
			(stroke
				(width 0.1)
				(type default)
			)
			(layer "F.Fab")
		)
		(fp_line
			(start 3.050032 2.999994)
			(end 3.050032 -2.999994)
			(stroke
				(width 0.1)
				(type default)
			)
			(layer "F.Fab")
		)
		(fp_line
			(start -3.050032 2.999994)
			(end 3.050032 2.999994)
			(stroke
				(width 0.1)
				(type default)
			)
			(layer "F.Fab")
		)
		(pad "1" smd rect
			(at -2.525014 0 90)
			(size 1.651 2.6162)
			(layers "F.Cu" "F.Mask" "F.Paste")
			(net "SW_P12V_AUX_PVDDCR_CPU1_P1_FLT")
		)
		(pad "2" smd rect
			(at 2.525014 0 90)
			(size 1.651 2.6162)
			(layers "F.Cu" "F.Mask" "F.Paste")
			(net "P12V_AUX")
		)
	)
	(footprint ""
		(layer "F.Cu")
		(at 163.743894 -120.37187)
		(property "Reference" "R6031"
			(at 0 0 0)
			(layer "F.SilkS")
			(hide yes)
			(effects
				(font
					(size 1.27 1.27)
				)
			)
		)
		(property "Value" ""
			(at 0 0 0)
			(layer "F.Fab")
			(effects
				(font
					(size 1.27 1.27)
				)
			)
		)
		(duplicate_pad_numbers_are_jumpers no)
		(fp_line
			(start -0.7874 -0.4064)
			(end 0.7874 -0.4064)
			(stroke
				(width 0.1524)
				(type default)
			)
			(layer "F.SilkS")
		)
		(fp_line
			(start -0.7874 0.4064)
			(end -0.7874 -0.4064)
			(stroke
				(width 0.1524)
				(type default)
			)
			(layer "F.SilkS")
		)
		(fp_line
			(start 0.7874 -0.4064)
			(end 0.7874 0.4064)
			(stroke
				(width 0.1524)
				(type default)
			)
			(layer "F.SilkS")
		)
		(fp_line
			(start 0.7874 0.4064)
			(end -0.7874 0.4064)
			(stroke
				(width 0.1524)
				(type default)
			)
			(layer "F.SilkS")
		)
		(fp_line
			(start -0.67945 -0.305054)
			(end -0.12065 -0.305054)
			(stroke
				(width 0.1)
				(type default)
			)
			(layer "F.Fab")
		)
		(fp_line
			(start -0.67945 0.3048)
			(end -0.67945 -0.305054)
			(stroke
				(width 0.1)
				(type default)
			)
			(layer "F.Fab")
		)
		(fp_line
			(start -0.12065 -0.305054)
			(end -0.12065 -0.2794)
			(stroke
				(width 0.1)
				(type default)
			)
			(layer "F.Fab")
		)
		(fp_line
			(start -0.12065 -0.2794)
			(end 0.12065 -0.2794)
			(stroke
				(width 0.1)
				(type default)
			)
			(layer "F.Fab")
		)
		(fp_line
			(start -0.12065 0.2794)
			(end -0.12065 0.3048)
			(stroke
				(width 0.1)
				(type default)
			)
			(layer "F.Fab")
		)
		(fp_line
			(start -0.12065 0.3048)
			(end -0.67945 0.3048)
			(stroke
				(width 0.1)
				(type default)
			)
			(layer "F.Fab")
		)
		(fp_line
			(start 0.120396 0.2794)
			(end -0.12065 0.2794)
			(stroke
				(width 0.1)
				(type default)
			)
			(layer "F.Fab")
		)
		(fp_line
			(start 0.120396 0.3048)
			(end 0.120396 0.2794)
			(stroke
				(width 0.1)
				(type default)
			)
			(layer "F.Fab")
		)
		(fp_line
			(start 0.12065 -0.3048)
			(end 0.67945 -0.3048)
			(stroke
				(width 0.1)
				(type default)
			)
			(layer "F.Fab")
		)
		(fp_line
			(start 0.12065 -0.2794)
			(end 0.12065 -0.3048)
			(stroke
				(width 0.1)
				(type default)
			)
			(layer "F.Fab")
		)
		(fp_line
			(start 0.67945 -0.3048)
			(end 0.67945 0.3048)
			(stroke
				(width 0.1)
				(type default)
			)
			(layer "F.Fab")
		)
		(fp_line
			(start 0.67945 0.3048)
			(end 0.120396 0.3048)
			(stroke
				(width 0.1)
				(type default)
			)
			(layer "F.Fab")
		)
		(pad "1" smd circle
			(at -0.40005 0)
			(size 0 0)
			(layers "F.Cu" "F.Mask" "F.Paste")
			(net "VIRTUAL_RESEAT_FPGA_N")
		)
		(pad "2" smd circle
			(at 0.40005 0)
			(size 0 0)
			(layers "F.Cu" "F.Mask" "F.Paste")
			(net "VIRTUAL_RESEAT_FPGA_R_N")
		)
	)
	(footprint ""
		(layer "F.Cu")
		(at 319.411096 -381.41783 -90)
		(property "Reference" "C911"
			(at 0 0 270)
			(layer "F.SilkS")
			(hide yes)
			(effects
				(font
					(size 1.27 1.27)
				)
			)
		)
		(property "Value" ""
			(at 0 0 270)
			(layer "F.Fab")
			(effects
				(font
					(size 1.27 1.27)
				)
			)
		)
		(duplicate_pad_numbers_are_jumpers no)
		(fp_line
			(start -0.299974 0.150114)
			(end -0.299974 -0.150114)
			(stroke
				(width 0.1)
				(type default)
			)
			(layer "F.Fab")
		)
		(fp_line
			(start 0.299974 0.150114)
			(end -0.299974 0.150114)
			(stroke
				(width 0.1)
				(type default)
			)
			(layer "F.Fab")
		)
		(fp_line
			(start -0.299974 -0.150114)
			(end 0.299974 -0.150114)
			(stroke
				(width 0.1)
				(type default)
			)
			(layer "F.Fab")
		)
		(fp_line
			(start 0.299974 -0.150114)
			(end 0.299974 0.150114)
			(stroke
				(width 0.1)
				(type default)
			)
			(layer "F.Fab")
		)
		(pad "1" smd rect
			(at -0.2667 0 270)
			(size 0.3048 0.381)
			(layers "F.Cu" "F.Mask" "F.Paste")
			(net "P5E_CPU0_P0_TX_C_DP<11>")
		)
		(pad "2" smd rect
			(at 0.2667 0 270)
			(size 0.3048 0.381)
			(layers "F.Cu" "F.Mask" "F.Paste")
			(net "P5E_CPU0_P0_TX_DP<11>")
		)
	)
	(footprint ""
		(layer "F.Cu")
		(at 112.048798 -171.808902 90)
		(property "Reference" "PC323_1"
			(at 0 0 90)
			(layer "F.SilkS")
			(hide yes)
			(effects
				(font
					(size 1.27 1.27)
				)
			)
		)
		(property "Value" ""
			(at 0 0 90)
			(layer "F.Fab")
			(effects
				(font
					(size 1.27 1.27)
				)
			)
		)
		(duplicate_pad_numbers_are_jumpers no)
		(fp_line
			(start 0.7874 -0.4064)
			(end 0.7874 0.4064)
			(stroke
				(width 0.1524)
				(type default)
			)
			(layer "F.SilkS")
		)
		(fp_line
			(start -0.7874 -0.4064)
			(end 0.7874 -0.4064)
			(stroke
				(width 0.1524)
				(type default)
			)
			(layer "F.SilkS")
		)
		(fp_line
			(start 0.7874 0.4064)
			(end -0.7874 0.4064)
			(stroke
				(width 0.1524)
				(type default)
			)
			(layer "F.SilkS")
		)
		(fp_line
			(start -0.7874 0.4064)
			(end -0.7874 -0.4064)
			(stroke
				(width 0.1524)
				(type default)
			)
			(layer "F.SilkS")
		)
		(fp_line
			(start -0.12065 -0.305054)
			(end -0.12065 -0.2794)
			(stroke
				(width 0.1)
				(type default)
			)
			(layer "F.Fab")
		)
		(fp_line
			(start -0.67945 -0.305054)
			(end -0.12065 -0.305054)
			(stroke
				(width 0.1)
				(type default)
			)
			(layer "F.Fab")
		)
		(fp_line
			(start 0.67945 -0.3048)
			(end 0.67945 0.3048)
			(stroke
				(width 0.1)
				(type default)
			)
			(layer "F.Fab")
		)
		(fp_line
			(start 0.12065 -0.3048)
			(end 0.67945 -0.3048)
			(stroke
				(width 0.1)
				(type default)
			)
			(layer "F.Fab")
		)
		(fp_line
			(start 0.12065 -0.2794)
			(end 0.12065 -0.3048)
			(stroke
				(width 0.1)
				(type default)
			)
			(layer "F.Fab")
		)
		(fp_line
			(start -0.12065 -0.2794)
			(end 0.12065 -0.2794)
			(stroke
				(width 0.1)
				(type default)
			)
			(layer "F.Fab")
		)
		(fp_line
			(start 0.120396 0.2794)
			(end -0.12065 0.2794)
			(stroke
				(width 0.1)
				(type default)
			)
			(layer "F.Fab")
		)
		(fp_line
			(start -0.12065 0.2794)
			(end -0.12065 0.3048)
			(stroke
				(width 0.1)
				(type default)
			)
			(layer "F.Fab")
		)
		(fp_line
			(start 0.67945 0.3048)
			(end 0.120396 0.3048)
			(stroke
				(width 0.1)
				(type default)
			)
			(layer "F.Fab")
		)
		(fp_line
			(start 0.120396 0.3048)
			(end 0.120396 0.2794)
			(stroke
				(width 0.1)
				(type default)
			)
			(layer "F.Fab")
		)
		(fp_line
			(start -0.12065 0.3048)
			(end -0.67945 0.3048)
			(stroke
				(width 0.1)
				(type default)
			)
			(layer "F.Fab")
		)
		(fp_line
			(start -0.67945 0.3048)
			(end -0.67945 -0.305054)
			(stroke
				(width 0.1)
				(type default)
			)
			(layer "F.Fab")
		)
		(pad "1" smd circle
			(at -0.40005 0 90)
			(size 0 0)
			(layers "F.Cu" "F.Mask" "F.Paste")
			(net "SW_P12V_AUX_PVDDCR_SOC_P1_FLT")
		)
		(pad "2" smd circle
			(at 0.40005 0 90)
			(size 0 0)
			(layers "F.Cu" "F.Mask" "F.Paste")
			(net "GND")
		)
	)
	(footprint ""
		(layer "F.Cu")
		(at 440.088782 -438.14746 -90)
		(property "Reference" "R4571"
			(at 0 0 270)
			(layer "F.SilkS")
			(hide yes)
			(effects
				(font
					(size 1.27 1.27)
				)
			)
		)
		(property "Value" ""
			(at 0 0 270)
			(layer "F.Fab")
			(effects
				(font
					(size 1.27 1.27)
				)
			)
		)
		(duplicate_pad_numbers_are_jumpers no)
		(fp_line
			(start -0.7874 0.4064)
			(end -0.7874 -0.4064)
			(stroke
				(width 0.1524)
				(type default)
			)
			(layer "F.SilkS")
		)
		(fp_line
			(start 0.7874 0.4064)
			(end -0.7874 0.4064)
			(stroke
				(width 0.1524)
				(type default)
			)
			(layer "F.SilkS")
		)
		(fp_line
			(start -0.7874 -0.4064)
			(end 0.7874 -0.4064)
			(stroke
				(width 0.1524)
				(type default)
			)
			(layer "F.SilkS")
		)
		(fp_line
			(start 0.7874 -0.4064)
			(end 0.7874 0.4064)
			(stroke
				(width 0.1524)
				(type default)
			)
			(layer "F.SilkS")
		)
		(fp_line
			(start -0.67945 0.3048)
			(end -0.67945 -0.305054)
			(stroke
				(width 0.1)
				(type default)
			)
			(layer "F.Fab")
		)
		(fp_line
			(start -0.12065 0.3048)
			(end -0.67945 0.3048)
			(stroke
				(width 0.1)
				(type default)
			)
			(layer "F.Fab")
		)
		(fp_line
			(start 0.120396 0.3048)
			(end 0.120396 0.2794)
			(stroke
				(width 0.1)
				(type default)
			)
			(layer "F.Fab")
		)
		(fp_line
			(start 0.67945 0.3048)
			(end 0.120396 0.3048)
			(stroke
				(width 0.1)
				(type default)
			)
			(layer "F.Fab")
		)
		(fp_line
			(start -0.12065 0.2794)
			(end -0.12065 0.3048)
			(stroke
				(width 0.1)
				(type default)
			)
			(layer "F.Fab")
		)
		(fp_line
			(start 0.120396 0.2794)
			(end -0.12065 0.2794)
			(stroke
				(width 0.1)
				(type default)
			)
			(layer "F.Fab")
		)
		(fp_line
			(start -0.12065 -0.2794)
			(end 0.12065 -0.2794)
			(stroke
				(width 0.1)
				(type default)
			)
			(layer "F.Fab")
		)
		(fp_line
			(start 0.12065 -0.2794)
			(end 0.12065 -0.3048)
			(stroke
				(width 0.1)
				(type default)
			)
			(layer "F.Fab")
		)
		(fp_line
			(start 0.12065 -0.3048)
			(end 0.67945 -0.3048)
			(stroke
				(width 0.1)
				(type default)
			)
			(layer "F.Fab")
		)
		(fp_line
			(start 0.67945 -0.3048)
			(end 0.67945 0.3048)
			(stroke
				(width 0.1)
				(type default)
			)
			(layer "F.Fab")
		)
		(fp_line
			(start -0.67945 -0.305054)
			(end -0.12065 -0.305054)
			(stroke
				(width 0.1)
				(type default)
			)
			(layer "F.Fab")
		)
		(fp_line
			(start -0.12065 -0.305054)
			(end -0.12065 -0.2794)
			(stroke
				(width 0.1)
				(type default)
			)
			(layer "F.Fab")
		)
		(pad "1" smd circle
			(at -0.40005 0 270)
			(size 0 0)
			(layers "F.Cu" "F.Mask" "F.Paste")
			(net "GPU_3V3IO_RSVD4")
		)
		(pad "2" smd circle
			(at 0.40005 0 270)
			(size 0 0)
			(layers "F.Cu" "F.Mask" "F.Paste")
			(net "GPU_3V3IO_RSVD4_ISO")
		)
	)
	(footprint ""
		(layer "F.Cu")
		(at 92.559632 -74.68362 180)
		(property "Reference" "PC2169"
			(at 0 0 180)
			(layer "F.SilkS")
			(hide yes)
			(effects
				(font
					(size 1.27 1.27)
				)
			)
		)
		(property "Value" ""
			(at 0 0 180)
			(layer "F.Fab")
			(effects
				(font
					(size 1.27 1.27)
				)
			)
		)
		(duplicate_pad_numbers_are_jumpers no)
		(fp_line
			(start 0.7874 0.4064)
			(end -0.7874 0.4064)
			(stroke
				(width 0.1524)
				(type default)
			)
			(layer "F.SilkS")
		)
		(fp_line
			(start 0.7874 -0.4064)
			(end 0.7874 0.4064)
			(stroke
				(width 0.1524)
				(type default)
			)
			(layer "F.SilkS")
		)
		(fp_line
			(start -0.7874 0.4064)
			(end -0.7874 -0.4064)
			(stroke
				(width 0.1524)
				(type default)
			)
			(layer "F.SilkS")
		)
		(fp_line
			(start -0.7874 -0.4064)
			(end 0.7874 -0.4064)
			(stroke
				(width 0.1524)
				(type default)
			)
			(layer "F.SilkS")
		)
		(fp_line
			(start 0.67945 0.3048)
			(end 0.120396 0.3048)
			(stroke
				(width 0.1)
				(type default)
			)
			(layer "F.Fab")
		)
		(fp_line
			(start 0.67945 -0.3048)
			(end 0.67945 0.3048)
			(stroke
				(width 0.1)
				(type default)
			)
			(layer "F.Fab")
		)
		(fp_line
			(start 0.12065 -0.2794)
			(end 0.12065 -0.3048)
			(stroke
				(width 0.1)
				(type default)
			)
			(layer "F.Fab")
		)
		(fp_line
			(start 0.12065 -0.3048)
			(end 0.67945 -0.3048)
			(stroke
				(width 0.1)
				(type default)
			)
			(layer "F.Fab")
		)
		(fp_line
			(start 0.120396 0.3048)
			(end 0.120396 0.2794)
			(stroke
				(width 0.1)
				(type default)
			)
			(layer "F.Fab")
		)
		(fp_line
			(start 0.120396 0.2794)
			(end -0.12065 0.2794)
			(stroke
				(width 0.1)
				(type default)
			)
			(layer "F.Fab")
		)
		(fp_line
			(start -0.12065 0.3048)
			(end -0.67945 0.3048)
			(stroke
				(width 0.1)
				(type default)
			)
			(layer "F.Fab")
		)
		(fp_line
			(start -0.12065 0.2794)
			(end -0.12065 0.3048)
			(stroke
				(width 0.1)
				(type default)
			)
			(layer "F.Fab")
		)
		(fp_line
			(start -0.12065 -0.2794)
			(end 0.12065 -0.2794)
			(stroke
				(width 0.1)
				(type default)
			)
			(layer "F.Fab")
		)
		(fp_line
			(start -0.12065 -0.305054)
			(end -0.12065 -0.2794)
			(stroke
				(width 0.1)
				(type default)
			)
			(layer "F.Fab")
		)
		(fp_line
			(start -0.67945 0.3048)
			(end -0.67945 -0.305054)
			(stroke
				(width 0.1)
				(type default)
			)
			(layer "F.Fab")
		)
		(fp_line
			(start -0.67945 -0.305054)
			(end -0.12065 -0.305054)
			(stroke
				(width 0.1)
				(type default)
			)
			(layer "F.Fab")
		)
		(pad "1" smd circle
			(at -0.40005 0 180)
			(size 0 0)
			(layers "F.Cu" "F.Mask" "F.Paste")
			(net "P3V3_AUX")
		)
		(pad "2" smd circle
			(at 0.40005 0 180)
			(size 0 0)
			(layers "F.Cu" "F.Mask" "F.Paste")
			(net "GND")
		)
	)
)
